# TIMECARD (Time Appliance Project (Time Card)) — schematic netlist excerpt (pin names and nets, part order shuffled) for the footprints in the layout excerpt that follows; sources: Cadence DE-HDL packaged netlist, KiCad conversion of R4006-B0001-02_R01.brd

U25  ISL80101IRAJZ_DFN10  pkg DFN11_118_P0197_TR057X071  page 31
  VOUT_1  = XP2R5V_FPGA
  VOUT_2  = XP2R5V_FPGA
  \sense/adj\  = UNNAMED_515_ISL80101IRAJZDFN10_
  PG  = UNNAMED_515_CAPACITOR_I138_1
  GND  = SG
  SS  = UNNAMED_515_CAPACITOR_I132_1
  ENABLE  = UNNAMED_515_CAPACITOR_I128_1
  NC  = NC
  VIN_1  = UNNAMED_515_CAPACITOR_I130_1
  VIN_2  = UNNAMED_515_CAPACITOR_I130_1
  THRM_PAD  = SG

(kicad_pcb
	(version 20260206)
	(generator "pcbnew")
	(generator_version "10.0")
	(general
		(thickness 1.6)
		(legacy_teardrops no)
	)
	(paper "A4")
	(title_block
		(title "timecard-production-celestica-r4006 — R4006-B0001-02_R01.brd")
		(comment 1 "Time Appliance Project (Time Card) / footprints 247-247 of 1113")
	)
	(layers
		(0 "F.Cu" signal "TOP")
		(4 "In1.Cu" signal "L02_GND1")
		(6 "In2.Cu" signal "L03_SIG1")
		(8 "In3.Cu" signal "L04_GND2")
		(10 "In4.Cu" signal "L05_VCC1")
		(12 "In5.Cu" signal "L06_VCC2")
		(14 "In6.Cu" signal "L07_GND3")
		(16 "In7.Cu" signal "L08_SIG2")
		(18 "In8.Cu" signal "L09_GND4")
		(2 "B.Cu" signal "BOTTOM")
		(9 "F.Adhes" user "F.Adhesive")
		(11 "B.Adhes" user "B.Adhesive")
		(13 "F.Paste" user "Package Geometry/Pastemask Top")
		(15 "B.Paste" user "Package Geometry/Pastemask Bottom")
		(5 "F.SilkS" user "Ref Des/Silkscreen Top")
		(7 "B.SilkS" user "Ref Des/Silkscreen Bottom")
		(1 "F.Mask" user "Board Geometry/Soldermask Top")
		(3 "B.Mask" user "Board Geometry/Soldermask Bottom")
		(17 "Dwgs.User" user "User.Drawings")
		(19 "Cmts.User" user "User.Comments")
		(21 "Eco1.User" user "User.Eco1")
		(23 "Eco2.User" user "User.Eco2")
		(25 "Edge.Cuts" user "Board Geometry/Outline")
		(27 "Margin" user)
		(31 "F.CrtYd" user "Package Geometry/Place Bound Top")
		(29 "B.CrtYd" user "Package Geometry/Place Bound Bottom")
		(35 "F.Fab" user "Ref Des/Assembly Top")
		(33 "B.Fab" user "Ref Des/Assembly Bottom")
	)
	(footprint ""
		(layer "F.Cu")
		(at 142.875 -17.2466)
		(property "Reference" "U25"
			(at -0.254 2.68097 0)
			(unlocked yes)
			(layer "F.SilkS")
			(effects
				(font
					(size 0.7874 0.5842)
					(thickness 0.1524)
				)
			)
		)
		(property "Value" ""
			(at 0 0 0)
			(layer "F.Fab")
			(effects
				(font
					(size 1.27 1.27)
				)
			)
		)
		(property "Device Type" "ISL80101IRAJZ_DFN10-G222-10136A"
			(at 0.276606 2.583688 0)
			(unlocked yes)
			(layer "F.Fab")
			(hide yes)
			(effects
				(font
					(size 0.7874 0.5842)
					(thickness 0.1524)
				)
			)
		)
		(property "User Part Number" "PARTNUM*"
			(at 0.276606 3.517646 0)
			(unlocked yes)
			(layer "Cmts.User")
			(hide yes)
			(effects
				(font
					(size 0.7874 0.5842)
					(thickness 0.1524)
				)
			)
		)
		(duplicate_pad_numbers_are_jumpers no)
		(fp_line
			(start -2.290318 -1.779016)
			(end 2.290318 -1.779016)
			(stroke
				(width 0.1)
				(type default)
			)
			(layer "F.SilkS")
		)
		(fp_line
			(start -2.290318 1.779016)
			(end -2.290318 -1.779016)
			(stroke
				(width 0.1)
				(type default)
			)
			(layer "F.SilkS")
		)
		(fp_line
			(start 2.290318 -1.779016)
			(end 2.290318 1.779016)
			(stroke
				(width 0.1)
				(type default)
			)
			(layer "F.SilkS")
		)
		(fp_line
			(start 2.290318 1.779016)
			(end -2.290318 1.779016)
			(stroke
				(width 0.1)
				(type default)
			)
			(layer "F.SilkS")
		)
		(fp_poly
			(pts
				(arc
					(start -2.553462 -1.023112)
					(mid -3.315462 -1.023112)
					(end -2.553462 -1.023112)
				)
			)
			(stroke
				(width 0)
				(type default)
			)
			(fill yes)
			(layer "F.SilkS")
		)
		(fp_poly
			(pts
				(xy -0.7239 -0.1016)
				(arc
					(start -0.7239 -0.6477)
					(mid -0.290295 -0.468095)
					(end -0.4699 -0.9017)
				)
				(xy 0.7239 -0.9017) (xy 0.7239 -0.1016)
			)
			(stroke
				(width 0)
				(type default)
			)
			(fill yes)
			(layer "F.Paste")
		)
		(fp_poly
			(pts
				(xy -0.7239 0.1016) (xy 0.7239 0.1016) (xy 0.7239 0.62992)
				(arc
					(start 0.723392 0.630428)
					(mid 0.643347 0.462032)
					(end 0.4699 0.3937)
				)
				(arc
					(start 0.4699 0.3937)
					(mid 0.290295 0.468095)
					(end 0.2159 0.6477)
				)
				(arc
					(start 0.2159 0.6477)
					(mid 0.284984 0.821833)
					(end 0.45466 0.901192)
				)
				(xy 0.45466 0.9017) (xy -0.7239 0.9017)
			)
			(stroke
				(width 0)
				(type default)
			)
			(fill yes)
			(layer "F.Paste")
		)
		(fp_poly
			(pts
				(xy -2.544318 2.033016) (xy 2.544318 2.033016) (xy 2.544318 -2.033016) (xy -2.544318 -2.033016)
			)
			(stroke
				(width 0)
				(type default)
			)
			(fill no)
			(layer "F.CrtYd")
		)
		(fp_line
			(start -1.525016 -1.525016)
			(end 1.525016 -1.525016)
			(stroke
				(width 0.1)
				(type default)
			)
			(layer "F.Fab")
		)
		(fp_line
			(start -1.525016 1.525016)
			(end -1.525016 -1.525016)
			(stroke
				(width 0.1)
				(type default)
			)
			(layer "F.Fab")
		)
		(fp_line
			(start 1.525016 -1.525016)
			(end 1.525016 1.525016)
			(stroke
				(width 0.1)
				(type default)
			)
			(layer "F.Fab")
		)
		(fp_line
			(start 1.525016 1.525016)
			(end -1.525016 1.525016)
			(stroke
				(width 0.1)
				(type default)
			)
			(layer "F.Fab")
		)
		(fp_poly
			(pts
				(arc
					(start -1.664462 -1.277112)
					(mid -2.426462 -1.277112)
					(end -1.664462 -1.277112)
				)
			)
			(stroke
				(width 0)
				(type default)
			)
			(fill yes)
			(layer "F.Fab")
		)
		(fp_text user "5"
			(at -2.921 1.41097 0)
			(unlocked yes)
			(layer "F.SilkS")
			(effects
				(font
					(size 0.7874 0.5842)
					(thickness 0.1524)
				)
			)
		)
		(fp_text user "6"
			(at 2.7559 1.202182 0)
			(unlocked yes)
			(layer "F.SilkS")
			(effects
				(font
					(size 0.7874 0.5842)
					(thickness 0.1524)
				)
			)
		)
		(fp_text user "5"
			(at -2.032 1.14427 0)
			(unlocked yes)
			(layer "F.Fab")
			(effects
				(font
					(size 0.7874 0.5842)
					(thickness 0.1524)
				)
			)
		)
		(fp_text user "6"
			(at 2.032 1.14427 0)
			(unlocked yes)
			(layer "F.Fab")
			(effects
				(font
					(size 0.7874 0.5842)
					(thickness 0.1524)
				)
			)
		)
		(fp_text user "10"
			(at 2.286 -1.39573 0)
			(unlocked yes)
			(layer "F.Fab")
			(effects
				(font
					(size 0.7874 0.5842)
					(thickness 0.1524)
				)
			)
		)
		(pad "1" smd circle
			(at -1.515618 -1.000252 180)
			(size 0 0)
			(layers "F.Cu" "F.Mask" "F.Paste")
			(net "XP2R5V_FPGA")
		)
		(pad "2" smd rect
			(at -1.515618 -0.500126)
			(size 1.0414 0.3048)
			(layers "F.Cu" "F.Mask" "F.Paste")
			(net "XP2R5V_FPGA")
		)
		(pad "3" smd rect
			(at -1.515618 0)
			(size 1.0414 0.3048)
			(layers "F.Cu" "F.Mask" "F.Paste")
			(net "UNNAMED_515_ISL80101IRAJZDFN10_")
		)
		(pad "4" smd rect
			(at -1.515618 0.500126)
			(size 1.0414 0.3048)
			(layers "F.Cu" "F.Mask" "F.Paste")
			(net "UNNAMED_515_CAPACITOR_I138_1")
		)
		(pad "5" smd circle
			(at -1.515618 1.000252)
			(size 0 0)
			(layers "F.Cu" "F.Mask" "F.Paste")
			(net "SG")
		)
		(pad "6" smd circle
			(at 1.515618 1.000252)
			(size 0 0)
			(layers "F.Cu" "F.Mask" "F.Paste")
			(net "UNNAMED_515_CAPACITOR_I132_1")
		)
		(pad "7" smd rect
			(at 1.515618 0.500126)
			(size 1.0414 0.3048)
			(layers "F.Cu" "F.Mask" "F.Paste")
			(net "UNNAMED_515_CAPACITOR_I128_1")
		)
		(pad "8" smd rect
			(at 1.515618 0)
			(size 1.0414 0.3048)
			(layers "F.Cu" "F.Mask" "F.Paste")
			(net "Net_764")
		)
		(pad "9" smd rect
			(at 1.515618 -0.500126)
			(size 1.0414 0.3048)
			(layers "F.Cu" "F.Mask" "F.Paste")
			(net "UNNAMED_515_CAPACITOR_I130_1")
		)
		(pad "10" smd circle
			(at 1.515618 -1.000252 180)
			(size 0 0)
			(layers "F.Cu" "F.Mask" "F.Paste")
			(net "UNNAMED_515_CAPACITOR_I130_1")
		)
		(pad "11" smd rect
			(at 0 0)
			(size 1.4478 1.8034)
			(layers "F.Cu" "F.Mask" "F.Paste")
			(net "SG")
		)
	)
)
